(kicad_sch
	(version 20231120)
	(generator "eeschema")
	(generator_version "8.0")
	(paper "A3")
	(title_block
		(title "GSML Serializer ")
		(date "2024-11-27")
		(rev "1.1.1")
		(company "Antmicro Ltd")
		(comment 1 "www.antmicro.com")
	)
	(bus_alias "I2C"
		(members "SDA" "SCL")
	)
	(junction
		(at 198.12 173.99)
		(diameter 0)
		(color 0 0 0 0)
	)
	(junction
		(at 167.64 143.51)
		(diameter 0)
		(color 0 0 0 0)
	)
	(junction
		(at 171.45 194.31)
		(diameter 0)
		(color 0 0 0 0)
	)
	(junction
		(at 254 193.04)
		(diameter 0)
		(color 0 0 0 0)
	)
	(junction
		(at 167.64 151.13)
		(diameter 0)
		(color 0 0 0 0)
	)
	(junction
		(at 167.64 105.41)
		(diameter 0)
		(color 0 0 0 0)
	)
	(junction
		(at 167.64 204.47)
		(diameter 0)
		(color 0 0 0 0)
	)
	(junction
		(at 212.09 163.83)
		(diameter 0)
		(color 0 0 0 0)
	)
	(junction
		(at 167.64 207.01)
		(diameter 0)
		(color 0 0 0 0)
	)
	(junction
		(at 170.18 161.29)
		(diameter 0)
		(color 0 0 0 0)
	)
	(junction
		(at 199.39 176.53)
		(diameter 0)
		(color 0 0 0 0)
	)
	(junction
		(at 214.63 176.53)
		(diameter 0)
		(color 0 0 0 0)
	)
	(junction
		(at 171.45 201.93)
		(diameter 0)
		(color 0 0 0 0)
	)
	(junction
		(at 257.81 187.96)
		(diameter 0)
		(color 0 0 0 0)
	)
	(junction
		(at 167.64 120.65)
		(diameter 0)
		(color 0 0 0 0)
	)
	(junction
		(at 167.64 113.03)
		(diameter 0)
		(color 0 0 0 0)
	)
	(junction
		(at 209.55 173.99)
		(diameter 0)
		(color 0 0 0 0)
	)
	(no_connect
		(at 161.29 107.95)
	)
	(no_connect
		(at 161.29 95.25)
	)
	(no_connect
		(at 161.29 82.55)
	)
	(no_connect
		(at 161.29 87.63)
	)
	(no_connect
		(at 266.7 170.18)
	)
	(no_connect
		(at 161.29 90.17)
	)
	(no_connect
		(at 161.29 77.47)
	)
	(no_connect
		(at 161.29 171.45)
	)
	(no_connect
		(at 161.29 158.75)
	)
	(no_connect
		(at 161.29 92.71)
	)
	(no_connect
		(at 161.29 184.15)
	)
	(no_connect
		(at 161.29 118.11)
	)
	(no_connect
		(at 161.29 189.23)
	)
	(no_connect
		(at 161.29 80.01)
	)
	(no_connect
		(at 161.29 110.49)
	)
	(no_connect
		(at 161.29 163.83)
	)
	(no_connect
		(at 161.29 102.87)
	)
	(no_connect
		(at 161.29 100.33)
	)
	(no_connect
		(at 161.29 166.37)
	)
	(no_connect
		(at 161.29 186.69)
	)
	(no_connect
		(at 161.29 153.67)
	)
	(no_connect
		(at 266.7 172.72)
	)
	(no_connect
		(at 161.29 85.09)
	)
	(no_connect
		(at 161.29 168.91)
	)
	(no_connect
		(at 161.29 191.77)
	)
	(no_connect
		(at 161.29 115.57)
	)
	(bus_entry
		(at 227.33 176.53)
		(size 1.27 -1.27)
		(stroke
			(width 0)
			(type default)
		)
	)
	(bus_entry
		(at 181.61 138.43)
		(size 1.27 -1.27)
		(stroke
			(width 0)
			(type default)
		)
	)
	(bus_entry
		(at 181.61 146.05)
		(size 1.27 -1.27)
		(stroke
			(width 0)
			(type default)
		)
	)
	(bus_entry
		(at 181.61 123.19)
		(size 1.27 -1.27)
		(stroke
			(width 0)
			(type default)
		)
	)
	(bus_entry
		(at 181.61 125.73)
		(size 1.27 -1.27)
		(stroke
			(width 0)
			(type default)
		)
	)
	(bus_entry
		(at 181.61 130.81)
		(size 1.27 -1.27)
		(stroke
			(width 0)
			(type default)
		)
	)
	(bus_entry
		(at 181.61 140.97)
		(size 1.27 -1.27)
		(stroke
			(width 0)
			(type default)
		)
	)
	(bus_entry
		(at 181.61 128.27)
		(size 1.27 -1.27)
		(stroke
			(width 0)
			(type default)
		)
	)
	(bus_entry
		(at 181.61 148.59)
		(size 1.27 -1.27)
		(stroke
			(width 0)
			(type default)
		)
	)
	(bus_entry
		(at 181.61 135.89)
		(size 1.27 -1.27)
		(stroke
			(width 0)
			(type default)
		)
	)
	(bus_entry
		(at 181.61 133.35)
		(size 1.27 -1.27)
		(stroke
			(width 0)
			(type default)
		)
	)
	(bus_entry
		(at 227.33 173.99)
		(size 1.27 -1.27)
		(stroke
			(width 0)
			(type default)
		)
	)
	(wire
		(pts
			(xy 212.09 161.29) (xy 212.09 163.83)
		)
		(stroke
			(width 0)
			(type default)
		)
	)
	(wire
		(pts
			(xy 180.34 166.37) (xy 185.42 166.37)
		)
		(stroke
			(width 0)
			(type default)
		)
	)
	(wire
		(pts
			(xy 167.64 120.65) (xy 167.64 143.51)
		)
		(stroke
			(width 0)
			(type default)
		)
	)
	(wire
		(pts
			(xy 161.29 128.27) (xy 181.61 128.27)
		)
		(stroke
			(width 0)
			(type default)
		)
	)
	(bus
		(pts
			(xy 229.87 170.18) (xy 228.6 170.18)
		)
		(stroke
			(width 0)
			(type default)
		)
	)
	(wire
		(pts
			(xy 167.64 113.03) (xy 167.64 120.65)
		)
		(stroke
			(width 0)
			(type default)
		)
	)
	(wire
		(pts
			(xy 167.64 120.65) (xy 161.29 120.65)
		)
		(stroke
			(width 0)
			(type default)
		)
	)
	(wire
		(pts
			(xy 161.29 135.89) (xy 181.61 135.89)
		)
		(stroke
			(width 0)
			(type default)
		)
	)
	(wire
		(pts
			(xy 266.7 198.12) (xy 265.43 198.12)
		)
		(stroke
			(width 0)
			(type default)
		)
	)
	(wire
		(pts
			(xy 254 193.04) (xy 266.7 193.04)
		)
		(stroke
			(width 0)
			(type default)
		)
	)
	(wire
		(pts
			(xy 161.29 196.85) (xy 171.45 196.85)
		)
		(stroke
			(width 0)
			(type default)
		)
	)
	(wire
		(pts
			(xy 170.18 161.29) (xy 175.26 161.29)
		)
		(stroke
			(width 0)
			(type default)
		)
	)
	(wire
		(pts
			(xy 190.5 179.07) (xy 198.12 179.07)
		)
		(stroke
			(width 0)
			(type default)
		)
	)
	(wire
		(pts
			(xy 170.18 166.37) (xy 170.18 161.29)
		)
		(stroke
			(width 0)
			(type default)
		)
	)
	(bus
		(pts
			(xy 186.69 120.65) (xy 182.88 120.65)
		)
		(stroke
			(width 0)
			(type default)
		)
	)
	(wire
		(pts
			(xy 190.5 173.99) (xy 198.12 173.99)
		)
		(stroke
			(width 0)
			(type default)
		)
	)
	(wire
		(pts
			(xy 254 146.05) (xy 266.7 146.05)
		)
		(stroke
			(width 0)
			(type default)
		)
	)
	(wire
		(pts
			(xy 266.7 153.67) (xy 265.43 153.67)
		)
		(stroke
			(width 0)
			(type default)
		)
	)
	(wire
		(pts
			(xy 167.64 143.51) (xy 161.29 143.51)
		)
		(stroke
			(width 0)
			(type default)
		)
	)
	(wire
		(pts
			(xy 254 148.59) (xy 266.7 148.59)
		)
		(stroke
			(width 0)
			(type default)
		)
	)
	(wire
		(pts
			(xy 171.45 201.93) (xy 173.99 201.93)
		)
		(stroke
			(width 0)
			(type default)
		)
	)
	(wire
		(pts
			(xy 161.29 179.07) (xy 185.42 179.07)
		)
		(stroke
			(width 0)
			(type default)
		)
	)
	(bus
		(pts
			(xy 182.88 134.62) (xy 182.88 137.16)
		)
		(stroke
			(width 0)
			(type default)
		)
	)
	(wire
		(pts
			(xy 171.45 199.39) (xy 171.45 201.93)
		)
		(stroke
			(width 0)
			(type default)
		)
	)
	(wire
		(pts
			(xy 198.12 173.99) (xy 209.55 173.99)
		)
		(stroke
			(width 0)
			(type default)
		)
	)
	(wire
		(pts
			(xy 161.29 146.05) (xy 181.61 146.05)
		)
		(stroke
			(width 0)
			(type default)
		)
	)
	(wire
		(pts
			(xy 167.64 151.13) (xy 167.64 204.47)
		)
		(stroke
			(width 0)
			(type default)
		)
	)
	(wire
		(pts
			(xy 180.34 161.29) (xy 185.42 161.29)
		)
		(stroke
			(width 0)
			(type default)
		)
	)
	(bus
		(pts
			(xy 182.88 127) (xy 182.88 129.54)
		)
		(stroke
			(width 0)
			(type default)
		)
	)
	(wire
		(pts
			(xy 167.64 204.47) (xy 167.64 207.01)
		)
		(stroke
			(width 0)
			(type default)
		)
	)
	(wire
		(pts
			(xy 161.29 148.59) (xy 181.61 148.59)
		)
		(stroke
			(width 0)
			(type default)
		)
	)
	(wire
		(pts
			(xy 190.5 176.53) (xy 199.39 176.53)
		)
		(stroke
			(width 0)
			(type default)
		)
	)
	(wire
		(pts
			(xy 161.29 201.93) (xy 171.45 201.93)
		)
		(stroke
			(width 0)
			(type default)
		)
	)
	(wire
		(pts
			(xy 266.7 175.26) (xy 265.43 175.26)
		)
		(stroke
			(width 0)
			(type default)
		)
	)
	(wire
		(pts
			(xy 199.39 181.61) (xy 199.39 176.53)
		)
		(stroke
			(width 0)
			(type default)
		)
	)
	(wire
		(pts
			(xy 167.64 143.51) (xy 167.64 151.13)
		)
		(stroke
			(width 0)
			(type default)
		)
	)
	(wire
		(pts
			(xy 173.99 201.93) (xy 173.99 200.66)
		)
		(stroke
			(width 0)
			(type default)
		)
	)
	(wire
		(pts
			(xy 171.45 194.31) (xy 173.99 194.31)
		)
		(stroke
			(width 0)
			(type default)
		)
	)
	(wire
		(pts
			(xy 167.64 113.03) (xy 161.29 113.03)
		)
		(stroke
			(width 0)
			(type default)
		)
	)
	(bus
		(pts
			(xy 182.88 124.46) (xy 182.88 127)
		)
		(stroke
			(width 0)
			(type default)
		)
	)
	(wire
		(pts
			(xy 161.29 181.61) (xy 185.42 181.61)
		)
		(stroke
			(width 0)
			(type default)
		)
	)
	(wire
		(pts
			(xy 161.29 194.31) (xy 171.45 194.31)
		)
		(stroke
			(width 0)
			(type default)
		)
	)
	(wire
		(pts
			(xy 254 143.51) (xy 266.7 143.51)
		)
		(stroke
			(width 0)
			(type default)
		)
	)
	(wire
		(pts
			(xy 161.29 207.01) (xy 167.64 207.01)
		)
		(stroke
			(width 0)
			(type default)
		)
	)
	(bus
		(pts
			(xy 182.88 132.08) (xy 182.88 134.62)
		)
		(stroke
			(width 0)
			(type default)
		)
	)
	(wire
		(pts
			(xy 198.12 179.07) (xy 198.12 173.99)
		)
		(stroke
			(width 0)
			(type default)
		)
	)
	(wire
		(pts
			(xy 171.45 194.31) (xy 171.45 196.85)
		)
		(stroke
			(width 0)
			(type default)
		)
	)
	(wire
		(pts
			(xy 161.29 176.53) (xy 185.42 176.53)
		)
		(stroke
			(width 0)
			(type default)
		)
	)
	(wire
		(pts
			(xy 254 193.04) (xy 254 195.58)
		)
		(stroke
			(width 0)
			(type default)
		)
	)
	(bus
		(pts
			(xy 182.88 129.54) (xy 182.88 132.08)
		)
		(stroke
			(width 0)
			(type default)
		)
	)
	(wire
		(pts
			(xy 266.7 195.58) (xy 254 195.58)
		)
		(stroke
			(width 0)
			(type default)
		)
	)
	(wire
		(pts
			(xy 266.7 190.5) (xy 257.81 190.5)
		)
		(stroke
			(width 0)
			(type default)
		)
	)
	(wire
		(pts
			(xy 161.29 130.81) (xy 181.61 130.81)
		)
		(stroke
			(width 0)
			(type default)
		)
	)
	(wire
		(pts
			(xy 167.64 105.41) (xy 161.29 105.41)
		)
		(stroke
			(width 0)
			(type default)
		)
	)
	(wire
		(pts
			(xy 209.55 171.45) (xy 209.55 173.99)
		)
		(stroke
			(width 0)
			(type default)
		)
	)
	(wire
		(pts
			(xy 214.63 166.37) (xy 214.63 163.83)
		)
		(stroke
			(width 0)
			(type default)
		)
	)
	(bus
		(pts
			(xy 182.88 137.16) (xy 182.88 139.7)
		)
		(stroke
			(width 0)
			(type default)
		)
	)
	(wire
		(pts
			(xy 209.55 166.37) (xy 209.55 163.83)
		)
		(stroke
			(width 0)
			(type default)
		)
	)
	(wire
		(pts
			(xy 209.55 173.99) (xy 227.33 173.99)
		)
		(stroke
			(width 0)
			(type default)
		)
	)
	(wire
		(pts
			(xy 161.29 204.47) (xy 167.64 204.47)
		)
		(stroke
			(width 0)
			(type default)
		)
	)
	(bus
		(pts
			(xy 182.88 144.78) (xy 182.88 147.32)
		)
		(stroke
			(width 0)
			(type default)
		)
	)
	(wire
		(pts
			(xy 161.29 140.97) (xy 181.61 140.97)
		)
		(stroke
			(width 0)
			(type default)
		)
	)
	(wire
		(pts
			(xy 161.29 123.19) (xy 181.61 123.19)
		)
		(stroke
			(width 0)
			(type default)
		)
	)
	(wire
		(pts
			(xy 161.29 161.29) (xy 170.18 161.29)
		)
		(stroke
			(width 0)
			(type default)
		)
	)
	(wire
		(pts
			(xy 167.64 97.79) (xy 167.64 105.41)
		)
		(stroke
			(width 0)
			(type default)
		)
	)
	(wire
		(pts
			(xy 161.29 138.43) (xy 181.61 138.43)
		)
		(stroke
			(width 0)
			(type default)
		)
	)
	(wire
		(pts
			(xy 199.39 176.53) (xy 214.63 176.53)
		)
		(stroke
			(width 0)
			(type default)
		)
	)
	(wire
		(pts
			(xy 167.64 105.41) (xy 167.64 113.03)
		)
		(stroke
			(width 0)
			(type default)
		)
	)
	(wire
		(pts
			(xy 161.29 97.79) (xy 167.64 97.79)
		)
		(stroke
			(width 0)
			(type default)
		)
	)
	(wire
		(pts
			(xy 265.43 175.26) (xy 265.43 176.53)
		)
		(stroke
			(width 0)
			(type default)
		)
	)
	(bus
		(pts
			(xy 182.88 139.7) (xy 182.88 144.78)
		)
		(stroke
			(width 0)
			(type default)
		)
	)
	(wire
		(pts
			(xy 257.81 187.96) (xy 266.7 187.96)
		)
		(stroke
			(width 0)
			(type default)
		)
	)
	(wire
		(pts
			(xy 254 151.13) (xy 266.7 151.13)
		)
		(stroke
			(width 0)
			(type default)
		)
	)
	(bus
		(pts
			(xy 228.6 172.72) (xy 228.6 175.26)
		)
		(stroke
			(width 0)
			(type default)
		)
	)
	(wire
		(pts
			(xy 161.29 125.73) (xy 181.61 125.73)
		)
		(stroke
			(width 0)
			(type default)
		)
	)
	(wire
		(pts
			(xy 167.64 151.13) (xy 161.29 151.13)
		)
		(stroke
			(width 0)
			(type default)
		)
	)
	(wire
		(pts
			(xy 209.55 163.83) (xy 212.09 163.83)
		)
		(stroke
			(width 0)
			(type default)
		)
	)
	(wire
		(pts
			(xy 214.63 171.45) (xy 214.63 176.53)
		)
		(stroke
			(width 0)
			(type default)
		)
	)
	(wire
		(pts
			(xy 173.99 194.31) (xy 173.99 193.04)
		)
		(stroke
			(width 0)
			(type default)
		)
	)
	(wire
		(pts
			(xy 214.63 163.83) (xy 212.09 163.83)
		)
		(stroke
			(width 0)
			(type default)
		)
	)
	(bus
		(pts
			(xy 182.88 121.92) (xy 182.88 124.46)
		)
		(stroke
			(width 0)
			(type default)
		)
	)
	(wire
		(pts
			(xy 190.5 181.61) (xy 199.39 181.61)
		)
		(stroke
			(width 0)
			(type default)
		)
	)
	(wire
		(pts
			(xy 161.29 173.99) (xy 185.42 173.99)
		)
		(stroke
			(width 0)
			(type default)
		)
	)
	(bus
		(pts
			(xy 228.6 170.18) (xy 228.6 172.72)
		)
		(stroke
			(width 0)
			(type default)
		)
	)
	(wire
		(pts
			(xy 161.29 199.39) (xy 171.45 199.39)
		)
		(stroke
			(width 0)
			(type default)
		)
	)
	(wire
		(pts
			(xy 265.43 153.67) (xy 265.43 154.94)
		)
		(stroke
			(width 0)
			(type default)
		)
	)
	(wire
		(pts
			(xy 167.64 207.01) (xy 167.64 213.36)
		)
		(stroke
			(width 0)
			(type default)
		)
	)
	(wire
		(pts
			(xy 254 165.1) (xy 266.7 165.1)
		)
		(stroke
			(width 0)
			(type default)
		)
	)
	(wire
		(pts
			(xy 161.29 156.21) (xy 185.42 156.21)
		)
		(stroke
			(width 0)
			(type default)
		)
	)
	(wire
		(pts
			(xy 257.81 190.5) (xy 257.81 187.96)
		)
		(stroke
			(width 0)
			(type default)
		)
	)
	(bus
		(pts
			(xy 182.88 120.65) (xy 182.88 121.92)
		)
		(stroke
			(width 0)
			(type default)
		)
	)
	(wire
		(pts
			(xy 254 167.64) (xy 266.7 167.64)
		)
		(stroke
			(width 0)
			(type default)
		)
	)
	(wire
		(pts
			(xy 265.43 198.12) (xy 265.43 199.39)
		)
		(stroke
			(width 0)
			(type default)
		)
	)
	(wire
		(pts
			(xy 175.26 166.37) (xy 170.18 166.37)
		)
		(stroke
			(width 0)
			(type default)
		)
	)
	(wire
		(pts
			(xy 161.29 133.35) (xy 181.61 133.35)
		)
		(stroke
			(width 0)
			(type default)
		)
	)
	(wire
		(pts
			(xy 214.63 176.53) (xy 227.33 176.53)
		)
		(stroke
			(width 0)
			(type default)
		)
	)
	(text "1V8	-> Framos trigger / AV trigger"
		(exclude_from_sim no)
		(at 116.205 160.655 0)
		(effects
			(font
				(size 1.27 1.27)
			)
			(justify left bottom)
		)
	)
	(text "TVS diodes"
		(exclude_from_sim no)
		(at 255.27 137.16 0)
		(effects
			(font
				(size 2.54 2.54)
				(thickness 0.508)
				(bold yes)
			)
			(justify left bottom)
		)
	)
	(text "3V3	-> Framos enable / AV trigger"
		(exclude_from_sim no)
		(at 116.205 155.575 0)
		(effects
			(font
				(size 1.27 1.27)
			)
			(justify left bottom)
		)
	)
	(text "FFC CSI Connector"
		(exclude_from_sim no)
		(at 139.7 67.31 0)
		(effects
			(font
				(size 2.54 2.54)
				(thickness 0.508)
				(bold yes)
			)
			(justify left bottom)
		)
	)
	(label "CSI.CLK_P"
		(at 181.61 148.59 180)
		(fields_autoplaced yes)
		(effects
			(font
				(size 1.27 1.27)
			)
			(justify right bottom)
		)
	)
	(label "GPIO4_1V8"
		(at 254 167.64 0)
		(fields_autoplaced yes)
		(effects
			(font
				(size 1.27 1.27)
			)
			(justify left bottom)
		)
	)
	(label "CSI.CLK_N"
		(at 181.61 146.05 180)
		(fields_autoplaced yes)
		(effects
			(font
				(size 1.27 1.27)
			)
			(justify right bottom)
		)
	)
	(label "CSI.D2_N"
		(at 181.61 128.27 180)
		(fields_autoplaced yes)
		(effects
			(font
				(size 1.27 1.27)
			)
			(justify right bottom)
		)
	)
	(label "SCL_CAM1"
		(at 254 151.13 0)
		(fields_autoplaced yes)
		(effects
			(font
				(size 1.27 1.27)
			)
			(justify left bottom)
		)
	)
	(label "CSI.D2_P"
		(at 181.61 130.81 180)
		(fields_autoplaced yes)
		(effects
			(font
				(size 1.27 1.27)
			)
			(justify right bottom)
		)
	)
	(label "SDA_CAM1"
		(at 168.91 179.07 0)
		(fields_autoplaced yes)
		(effects
			(font
				(size 1.27 1.27)
			)
			(justify left bottom)
		)
	)
	(label "SCL_CAM0"
		(at 254 146.05 0)
		(fields_autoplaced yes)
		(effects
			(font
				(size 1.27 1.27)
			)
			(justify left bottom)
		)
	)
	(label "SCL_CAM1"
		(at 168.91 181.61 0)
		(fields_autoplaced yes)
		(effects
			(font
				(size 1.27 1.27)
			)
			(justify left bottom)
		)
	)
	(label "CSI.D1_N"
		(at 181.61 133.35 180)
		(fields_autoplaced yes)
		(effects
			(font
				(size 1.27 1.27)
			)
			(justify right bottom)
		)
	)
	(label "GPIO3"
		(at 254 165.1 0)
		(fields_autoplaced yes)
		(effects
			(font
				(size 1.27 1.27)
			)
			(justify left bottom)
		)
	)
	(label "CSI.D1_P"
		(at 181.61 135.89 180)
		(fields_autoplaced yes)
		(effects
			(font
				(size 1.27 1.27)
			)
			(justify right bottom)
		)
	)
	(label "CSI.D3_N"
		(at 181.61 123.19 180)
		(fields_autoplaced yes)
		(effects
			(font
				(size 1.27 1.27)
			)
			(justify right bottom)
		)
	)
	(label "SDA_CAM1"
		(at 254 148.59 0)
		(fields_autoplaced yes)
		(effects
			(font
				(size 1.27 1.27)
			)
			(justify left bottom)
		)
	)
	(label "CSI.D3_P"
		(at 181.61 125.73 180)
		(fields_autoplaced yes)
		(effects
			(font
				(size 1.27 1.27)
			)
			(justify right bottom)
		)
	)
	(label "CSI.D0_P"
		(at 181.61 140.97 180)
		(fields_autoplaced yes)
		(effects
			(font
				(size 1.27 1.27)
			)
			(justify right bottom)
		)
	)
	(label "SDA_CAM0"
		(at 168.91 173.99 0)
		(fields_autoplaced yes)
		(effects
			(font
				(size 1.27 1.27)
			)
			(justify left bottom)
		)
	)
	(label "GPIO4_1V8"
		(at 161.29 161.29 0)
		(fields_autoplaced yes)
		(effects
			(font
				(size 1.27 1.27)
			)
			(justify left bottom)
		)
	)
	(label "SDA_CAM0"
		(at 254 143.51 0)
		(fields_autoplaced yes)
		(effects
			(font
				(size 1.27 1.27)
			)
			(justify left bottom)
		)
	)
	(label "SCL_CAM0"
		(at 168.91 176.53 0)
		(fields_autoplaced yes)
		(effects
			(font
				(size 1.27 1.27)
			)
			(justify left bottom)
		)
	)
	(label "CSI.D0_N"
		(at 181.61 138.43 180)
		(fields_autoplaced yes)
		(effects
			(font
				(size 1.27 1.27)
			)
			(justify right bottom)
		)
	)
	(label "I2C.SDA"
		(at 219.71 173.99 0)
		(fields_autoplaced yes)
		(effects
			(font
				(size 1.27 1.27)
			)
			(justify left bottom)
		)
	)
	(label "I2C.SCL"
		(at 219.71 176.53 0)
		(fields_autoplaced yes)
		(effects
			(font
				(size 1.27 1.27)
			)
			(justify left bottom)
		)
	)
	(hierarchical_label "GPIO4"
		(shape input)
		(at 185.42 161.29 0)
		(fields_autoplaced yes)
		(effects
			(font
				(size 1.27 1.27)
			)
			(justify left)
		)
	)
	(hierarchical_label "CSI{CSI}"
		(shape output)
		(at 186.69 120.65 0)
		(fields_autoplaced yes)
		(effects
			(font
				(size 1.27 1.27)
			)
			(justify left)
		)
	)
	(hierarchical_label "GPIO3"
		(shape input)
		(at 185.42 156.21 0)
		(fields_autoplaced yes)
		(effects
			(font
				(size 1.27 1.27)
			)
			(justify left)
		)
	)
	(hierarchical_label "I2C{I2C}"
		(shape bidirectional)
		(at 229.87 170.18 0)
		(fields_autoplaced yes)
		(effects
			(font
				(size 1.27 1.27)
			)
			(justify left)
		)
	)
	(symbol
		(lib_id "antmicroTVSDiodes:PESD4USB5U-TTS")
		(at 266.7 165.1 0)
		(unit 1)
		(exclude_from_sim no)
		(in_bom yes)
		(on_board yes)
		(dnp no)
		(property "Reference" "D3"
			(at 269.24 162.56 0)
			(effects
				(font
					(size 1.27 1.27)
					(thickness 0.15)
				)
				(justify left)
			)
		)
		(property "Value" "PESD4USB5U-TTS"
			(at 280.67 163.195 0)
			(effects
				(font
					(size 1.27 1.27)
					(thickness 0.15)
				)
				(justify left bottom)
				(hide yes)
			)
		)
		(property "Footprint" "antmicro-footprints:DFN-10_2.5x1mm"
			(at 280.67 165.735 0)
			(effects
				(font
					(size 1.27 1.27)
					(thickness 0.15)
				)
				(justify left bottom)
				(hide yes)
			)
		)
		(property "Datasheet" "https://assets.nexperia.com/documents/data-sheet/PESD4USB5U-TTS.pdf"
			(at 280.67 168.275 0)
			(effects
				(font
					(size 1.27 1.27)
					(thickness 0.15)
				)
				(justify left bottom)
				(hide yes)
			)
		)
		(property "Description" ""
			(at 266.7 165.1 0)
			(effects
				(font
					(size 1.27 1.27)
				)
				(hide yes)
			)
		)
		(property "MPN" "PESD4USB5U-TTS"
			(at 269.24 177.8 0)
			(effects
				(font
					(size 1.27 1.27)
					(thickness 0.15)
				)
				(justify left)
			)
		)
		(property "Manufacturer" "Nexperia"
			(at 280.67 173.355 0)
			(effects
				(font
					(size 1.27 1.27)
					(thickness 0.15)
				)
				(justify left bottom)
				(hide yes)
			)
		)
		(property "Author" "Antmicro"
			(at 280.67 175.895 0)
			(effects
				(font
					(size 1.27 1.27)
					(thickness 0.15)
				)
				(justify left bottom)
				(hide yes)
			)
		)
		(property "License" "Apache-2.0"
			(at 280.67 178.435 0)
			(effects
				(font
					(size 1.27 1.27)
					(thickness 0.15)
				)
				(justify left bottom)
				(hide yes)
			)
		)
		(pin "1"
		)
		(pin "10"
		)
		(pin "2"
		)
		(pin "3"
		)
		(pin "4"
		)
		(pin "5"
		)
		(pin "6"
		)
		(pin "7"
		)
		(pin "8"
		)
		(pin "9"
		)
		(instances
			(project "gmsl-serializer"
				(path ""
					(reference "D3")
					(unit 1)
				)
			)
		)
	)
	(symbol
		(lib_id "antmicroResistors0402:R_4k7_0402")
		(at 209.55 171.45 270)
		(mirror x)
		(unit 1)
		(exclude_from_sim no)
		(in_bom yes)
		(on_board yes)
		(dnp no)
		(property "Reference" "R5"
			(at 204.47 167.64 90)
			(effects
				(font
					(size 1.27 1.27)
					(thickness 0.15)
				)
				(justify left)
			)
		)
		(property "Value" "R_4k7_0402"
			(at 196.85 151.13 0)
			(effects
				(font
					(size 1.27 1.27)
					(thickness 0.15)
				)
				(justify left bottom)
				(hide yes)
			)
		)
		(property "Footprint" "antmicro-footprints:R_0402_1005Metric"
			(at 194.31 151.13 0)
			(effects
				(font
					(size 1.27 1.27)
					(thickness 0.15)
				)
				(justify left bottom)
				(hide yes)
			)
		)
		(property "Datasheet" "https://www.bourns.com/docs/product-datasheets/cr.pdf"
			(at 191.77 151.13 0)
			(effects
				(font
					(size 1.27 1.27)
					(thickness 0.15)
				)
				(justify left bottom)
				(hide yes)
			)
		)
		(property "Description" ""
			(at 209.55 171.45 0)
			(effects
				(font
					(size 1.27 1.27)
				)
				(hide yes)
			)
		)
		(property "MPN" "CR0402-FX-4701GLF"
			(at 189.23 151.13 0)
			(effects
				(font
					(size 1.27 1.27)
					(thickness 0.15)
				)
				(justify left bottom)
				(hide yes)
			)
		)
		(property "Manufacturer" "Bourns"
			(at 186.69 151.13 0)
			(effects
				(font
					(size 1.27 1.27)
					(thickness 0.15)
				)
				(justify left bottom)
				(hide yes)
			)
		)
		(property "License" "Apache-2.0"
			(at 184.15 151.13 0)
			(effects
				(font
					(size 1.27 1.27)
					(thickness 0.15)
				)
				(justify left bottom)
				(hide yes)
			)
		)
		(property "Author" "Antmicro"
			(at 181.61 151.13 0)
			(effects
				(font
					(size 1.27 1.27)
					(thickness 0.15)
				)
				(justify left bottom)
				(hide yes)
			)
		)
		(property "Val" "4k7"
			(at 204.47 170.18 90)
			(effects
				(font
					(size 1.27 1.27)
					(thickness 0.15)
				)
				(justify left)
			)
		)
		(property "Tolerance" "1%"
			(at 199.39 151.13 0)
			(effects
				(font
					(size 1.27 1.27)
				)
				(justify left bottom)
				(hide yes)
			)
		)
		(pin "1"
		)
		(pin "2"
		)
		(instances
			(project "gmsl-serializer"
				(path ""
					(reference "R5")
					(unit 1)
				)
			)
		)
	)
	(symbol
		(lib_id "antmicropower:GND")
		(at 265.43 199.39 0)
		(unit 1)
		(exclude_from_sim no)
		(in_bom yes)
		(on_board yes)
		(dnp no)
		(property "Reference" "#PWR0114"
			(at 274.32 201.93 0)
			(effects
				(font
					(size 1.27 1.27)
					(thickness 0.15)
				)
				(justify left bottom)
				(hide yes)
			)
		)
		(property "Value" "GND"
			(at 265.43 203.2 0)
			(effects
				(font
					(size 1.27 1.27)
					(thickness 0.15)
				)
			)
		)
		(property "Footprint" ""
			(at 274.32 207.01 0)
			(effects
				(font
					(size 1.27 1.27)
					(thickness 0.15)
				)
				(justify left bottom)
				(hide yes)
			)
		)
		(property "Datasheet" ""
			(at 274.32 212.09 0)
			(effects
				(font
					(size 1.27 1.27)
					(thickness 0.15)
				)
				(justify left bottom)
				(hide yes)
			)
		)
		(property "Description" ""
			(at 265.43 199.39 0)
			(effects
				(font
					(size 1.27 1.27)
				)
				(hide yes)
			)
		)
		(property "Author" "Antmicro"
			(at 274.32 207.01 0)
			(effects
				(font
					(size 1.27 1.27)
					(thickness 0.15)
				)
				(justify left bottom)
				(hide yes)
			)
		)
		(property "License" "Apache-2.0"
			(at 274.32 209.55 0)
			(effects
				(font
					(size 1.27 1.27)
					(thickness 0.15)
				)
				(justify left bottom)
				(hide yes)
			)
		)
		(pin "1"
		)
		(instances
			(project "gmsl-serializer"
				(path ""
					(reference "#PWR0114")
					(unit 1)
				)
			)
		)
	)
	(symbol
		(lib_id "antmicropower:GND")
		(at 167.64 213.36 0)
		(unit 1)
		(exclude_from_sim no)
		(in_bom yes)
		(on_board yes)
		(dnp no)
		(fields_autoplaced yes)
		(property "Reference" "#PWR0101"
			(at 176.53 215.9 0)
			(effects
				(font
					(size 1.27 1.27)
					(thickness 0.15)
				)
				(justify left bottom)
				(hide yes)
			)
		)
		(property "Value" "GND"
			(at 167.64 218.44 0)
			(effects
				(font
					(size 1.27 1.27)
					(thickness 0.15)
				)
			)
		)
		(property "Footprint" ""
			(at 176.53 220.98 0)
			(effects
				(font
					(size 1.27 1.27)
					(thickness 0.15)
				)
				(justify left bottom)
				(hide yes)
			)
		)
		(property "Datasheet" ""
			(at 176.53 226.06 0)
			(effects
				(font
					(size 1.27 1.27)
					(thickness 0.15)
				)
				(justify left bottom)
				(hide yes)
			)
		)
		(property "Description" ""
			(at 167.64 213.36 0)
			(effects
				(font
					(size 1.27 1.27)
				)
				(hide yes)
			)
		)
		(property "Author" "Antmicro"
			(at 176.53 220.98 0)
			(effects
				(font
					(size 1.27 1.27)
					(thickness 0.15)
				)
				(justify left bottom)
				(hide yes)
			)
		)
		(property "License" "Apache-2.0"
			(at 176.53 223.52 0)
			(effects
				(font
					(size 1.27 1.27)
					(thickness 0.15)
				)
				(justify left bottom)
				(hide yes)
			)
		)
		(pin "1"
		)
		(instances
			(project "gmsl-serializer"
				(path ""
					(reference "#PWR0101")
					(unit 1)
				)
			)
		)
	)
	(symbol
		(lib_id "antmicropower:+5V")
		(at 173.99 200.66 0)
		(unit 1)
		(exclude_from_sim no)
		(in_bom yes)
		(on_board yes)
		(dnp no)
		(property "Reference" "#PWR02"
			(at 189.23 203.2 0)
			(effects
				(font
					(size 1.27 1.27)
					(thickness 0.15)
				)
				(justify left bottom)
				(hide yes)
			)
		)
		(property "Value" "+5V"
			(at 173.99 196.85 0)
			(effects
				(font
					(size 1.27 1.27)
					(thickness 0.15)
				)
			)
		)
		(property "Footprint" ""
			(at 189.23 208.28 0)
			(effects
				(font
					(size 1.27 1.27)
					(thickness 0.15)
				)
				(justify left bottom)
				(hide yes)
			)
		)
		(property "Datasheet" ""
			(at 189.23 210.82 0)
			(effects
				(font
					(size 1.27 1.27)
					(thickness 0.15)
				)
				(justify left bottom)
				(hide yes)
			)
		)
		(property "Description" ""
			(at 173.99 200.66 0)
			(effects
				(font
					(size 1.27 1.27)
				)
				(hide yes)
			)
		)
		(property "Author" "Antmicro"
			(at 189.23 208.28 0)
			(effects
				(font
					(size 1.27 1.27)
					(thickness 0.15)
				)
				(justify left bottom)
				(hide yes)
			)
		)
		(property "License" "Apache-2.0"
			(at 189.23 210.82 0)
			(effects
				(font
					(size 1.27 1.27)
					(thickness 0.15)
				)
				(justify left bottom)
				(hide yes)
			)
		)
		(pin "1"
		)
		(instances
			(project "gmsl-serializer"
				(path ""
					(reference "#PWR02")
					(unit 1)
				)
			)
		)
	)
	(symbol
		(lib_id "antmicropower:+3V3")
		(at 212.09 161.29 0)
		(unit 1)
		(exclude_from_sim no)
		(in_bom yes)
		(on_board yes)
		(dnp no)
		(fields_autoplaced yes)
		(property "Reference" "#PWR0105"
			(at 227.33 163.83 0)
			(effects
				(font
					(size 1.27 1.27)
					(thickness 0.15)
				)
				(justify left bottom)
				(hide yes)
			)
		)
		(property "Value" "+3V3"
			(at 212.09 156.21 0)
			(effects
				(font
					(size 1.27 1.27)
					(thickness 0.15)
				)
			)
		)
		(property "Footprint" ""
			(at 227.33 168.91 0)
			(effects
				(font
					(size 1.27 1.27)
					(thickness 0.15)
				)
				(justify left bottom)
				(hide yes)
			)
		)
		(property "Datasheet" ""
			(at 227.33 171.45 0)
			(effects
				(font
					(size 1.27 1.27)
					(thickness 0.15)
				)
				(justify left bottom)
				(hide yes)
			)
		)
		(property "Description" ""
			(at 212.09 161.29 0)
			(effects
				(font
					(size 1.27 1.27)
				)
				(hide yes)
			)
		)
		(property "Author" "Antmicro"
			(at 227.33 168.91 0)
			(effects
				(font
					(size 1.27 1.27)
					(thickness 0.15)
				)
				(justify left bottom)
				(hide yes)
			)
		)
		(property "License" "Apache-2.0"
			(at 227.33 171.45 0)
			(effects
				(font
					(size 1.27 1.27)
					(thickness 0.15)
				)
				(justify left bottom)
				(hide yes)
			)
		)
		(pin "1"
		)
		(instances
			(project "gmsl-serializer"
				(path ""
					(reference "#PWR0105")
					(unit 1)
				)
			)
		)
	)
	(symbol
		(lib_id "antmicropower:+5V")
		(at 254 193.04 0)
		(unit 1)
		(exclude_from_sim no)
		(in_bom yes)
		(on_board yes)
		(dnp no)
		(property "Reference" "#PWR0155"
			(at 269.24 195.58 0)
			(effects
				(font
					(size 1.27 1.27)
					(thickness 0.15)
				)
				(justify left bottom)
				(hide yes)
			)
		)
		(property "Value" "+5V"
			(at 254 189.23 0)
			(effects
				(font
					(size 1.27 1.27)
					(thickness 0.15)
				)
			)
		)
		(property "Footprint" ""
			(at 269.24 200.66 0)
			(effects
				(font
					(size 1.27 1.27)
					(thickness 0.15)
				)
				(justify left bottom)
				(hide yes)
			)
		)
		(property "Datasheet" ""
			(at 269.24 203.2 0)
			(effects
				(font
					(size 1.27 1.27)
					(thickness 0.15)
				)
				(justify left bottom)
				(hide yes)
			)
		)
		(property "Description" ""
			(at 254 193.04 0)
			(effects
				(font
					(size 1.27 1.27)
				)
				(hide yes)
			)
		)
		(property "Author" "Antmicro"
			(at 269.24 200.66 0)
			(effects
				(font
					(size 1.27 1.27)
					(thickness 0.15)
				)
				(justify left bottom)
				(hide yes)
			)
		)
		(property "License" "Apache-2.0"
			(at 269.24 203.2 0)
			(effects
				(font
					(size 1.27 1.27)
					(thickness 0.15)
				)
				(justify left bottom)
				(hide yes)
			)
		)
		(pin "1"
		)
		(instances
			(project "gmsl-serializer"
				(path ""
					(reference "#PWR0155")
					(unit 1)
				)
			)
		)
	)
	(symbol
		(lib_id "antmicropower:GND")
		(at 185.42 166.37 90)
		(unit 1)
		(exclude_from_sim no)
		(in_bom yes)
		(on_board yes)
		(dnp no)
		(fields_autoplaced yes)
		(property "Reference" "#PWR0102"
			(at 187.96 157.48 0)
			(effects
				(font
					(size 1.27 1.27)
					(thickness 0.15)
				)
				(justify left bottom)
				(hide yes)
			)
		)
		(property "Value" "GND"
			(at 189.23 166.3699 90)
			(effects
				(font
					(size 1.27 1.27)
					(thickness 0.15)
				)
				(justify right)
			)
		)
		(property "Footprint" ""
			(at 193.04 157.48 0)
			(effects
				(font
					(size 1.27 1.27)
					(thickness 0.15)
				)
				(justify left bottom)
				(hide yes)
			)
		)
		(property "Datasheet" ""
			(at 198.12 157.48 0)
			(effects
				(font
					(size 1.27 1.27)
					(thickness 0.15)
				)
				(justify left bottom)
				(hide yes)
			)
		)
		(property "Description" ""
			(at 185.42 166.37 0)
			(effects
				(font
					(size 1.27 1.27)
				)
				(hide yes)
			)
		)
		(property "Author" "Antmicro"
			(at 193.04 157.48 0)
			(effects
				(font
					(size 1.27 1.27)
					(thickness 0.15)
				)
				(justify left bottom)
				(hide yes)
			)
		)
		(property "License" "Apache-2.0"
			(at 195.58 157.48 0)
			(effects
				(font
					(size 1.27 1.27)
					(thickness 0.15)
				)
				(justify left bottom)
				(hide yes)
			)
		)
		(pin "1"
		)
		(instances
			(project "gmsl-serializer"
				(path ""
					(reference "#PWR0102")
					(unit 1)
				)
			)
		)
	)
	(symbol
		(lib_id "antmicroResistors0402:R_12k_0402")
		(at 175.26 166.37 0)
		(unit 1)
		(exclude_from_sim no)
		(in_bom yes)
		(on_board yes)
		(dnp no)
		(property "Reference" "R2"
			(at 173.99 167.64 0)
			(effects
				(font
					(size 1.27 1.27)
					(thickness 0.15)
				)
			)
		)
		(property "Value" "R_12k_0402"
			(at 195.58 179.07 0)
			(effects
				(font
					(size 1.27 1.27)
					(thickness 0.15)
				)
				(justify left bottom)
				(hide yes)
			)
		)
		(property "Footprint" "antmicro-footprints:R_0402_1005Metric"
			(at 195.58 181.61 0)
			(effects
				(font
					(size 1.27 1.27)
					(thickness 0.15)
				)
				(justify left bottom)
				(hide yes)
			)
		)
		(property "Datasheet" "https://www.bourns.com/docs/product-datasheets/cr.pdf"
			(at 195.58 184.15 0)
			(effects
				(font
					(size 1.27 1.27)
					(thickness 0.15)
				)
				(justify left bottom)
				(hide yes)
			)
		)
		(property "Description" ""
			(at 175.26 166.37 0)
			(effects
				(font
					(size 1.27 1.27)
				)
				(hide yes)
			)
		)
		(property "MPN" "CR0402-FX-1202GLF"
			(at 195.58 186.69 0)
			(effects
				(font
					(size 1.27 1.27)
					(thickness 0.15)
				)
				(justify left bottom)
				(hide yes)
			)
		)
		(property "Manufacturer" "Bourns"
			(at 195.58 189.23 0)
			(effects
				(font
					(size 1.27 1.27)
					(thickness 0.15)
				)
				(justify left bottom)
				(hide yes)
			)
		)
		(property "License" "Apache-2.0"
			(at 195.58 191.77 0)
			(effects
				(font
					(size 1.27 1.27)
					(thickness 0.15)
				)
				(justify left bottom)
				(hide yes)
			)
		)
		(property "Author" "Antmicro"
			(at 195.58 194.31 0)
			(effects
				(font
					(size 1.27 1.27)
					(thickness 0.15)
				)
				(justify left bottom)
				(hide yes)
			)
		)
		(property "Val" "12k"
			(at 181.61 167.64 0)
			(effects
				(font
					(size 1.27 1.27)
					(thickness 0.15)
				)
			)
		)
		(property "Tolerance" "1%"
			(at 195.58 176.53 0)
			(effects
				(font
					(size 1.27 1.27)
				)
				(justify left bottom)
				(hide yes)
			)
		)
		(pin "1"
		)
		(pin "2"
		)
		(instances
			(project "gmsl-serializer"
				(path ""
					(reference "R2")
					(unit 1)
				)
			)
		)
	)
	(symbol
		(lib_id "antmicropower:+3V3")
		(at 257.81 187.96 0)
		(unit 1)
		(exclude_from_sim no)
		(in_bom yes)
		(on_board yes)
		(dnp no)
		(property "Reference" "#PWR04"
			(at 273.05 190.5 0)
			(effects
				(font
					(size 1.27 1.27)
					(thickness 0.15)
				)
				(justify left bottom)
				(hide yes)
			)
		)
		(property "Value" "+3V3"
			(at 257.81 184.15 0)
			(effects
				(font
					(size 1.27 1.27)
					(thickness 0.15)
				)
			)
		)
		(property "Footprint" ""
			(at 273.05 195.58 0)
			(effects
				(font
					(size 1.27 1.27)
					(thickness 0.15)
				)
				(justify left bottom)
				(hide yes)
			)
		)
		(property "Datasheet" ""
			(at 273.05 198.12 0)
			(effects
				(font
					(size 1.27 1.27)
					(thickness 0.15)
				)
				(justify left bottom)
				(hide yes)
			)
		)
		(property "Description" ""
			(at 257.81 187.96 0)
			(effects
				(font
					(size 1.27 1.27)
				)
				(hide yes)
			)
		)
		(property "Author" "Antmicro"
			(at 273.05 195.58 0)
			(effects
				(font
					(size 1.27 1.27)
					(thickness 0.15)
				)
				(justify left bottom)
				(hide yes)
			)
		)
		(property "License" "Apache-2.0"
			(at 273.05 198.12 0)
			(effects
				(font
					(size 1.27 1.27)
					(thickness 0.15)
				)
				(justify left bottom)
				(hide yes)
			)
		)
		(pin "1"
		)
		(instances
			(project "gmsl-serializer"
				(path ""
					(reference "#PWR04")
					(unit 1)
				)
			)
		)
	)
	(symbol
		(lib_id "antmicroTVSDiodes:PESD4USB5U-TTS")
		(at 266.7 143.51 0)
		(unit 1)
		(exclude_from_sim no)
		(in_bom yes)
		(on_board yes)
		(dnp no)
		(property "Reference" "D1"
			(at 269.24 140.97 0)
			(effects
				(font
					(size 1.27 1.27)
					(thickness 0.15)
				)
				(justify left)
			)
		)
		(property "Value" "PESD4USB5U-TTS"
			(at 280.67 141.605 0)
			(effects
				(font
					(size 1.27 1.27)
					(thickness 0.15)
				)
				(justify left bottom)
				(hide yes)
			)
		)
		(property "Footprint" "antmicro-footprints:DFN-10_2.5x1mm"
			(at 280.67 144.145 0)
			(effects
				(font
					(size 1.27 1.27)
					(thickness 0.15)
				)
				(justify left bottom)
				(hide yes)
			)
		)
		(property "Datasheet" "https://assets.nexperia.com/documents/data-sheet/PESD4USB5U-TTS.pdf"
			(at 280.67 146.685 0)
			(effects
				(font
					(size 1.27 1.27)
					(thickness 0.15)
				)
				(justify left bottom)
				(hide yes)
			)
		)
		(property "Description" ""
			(at 266.7 143.51 0)
			(effects
				(font
					(size 1.27 1.27)
				)
				(hide yes)
			)
		)
		(property "MPN" "PESD4USB5U-TTS"
			(at 269.24 156.21 0)
			(effects
				(font
					(size 1.27 1.27)
					(thickness 0.15)
				)
				(justify left)
			)
		)
		(property "Manufacturer" "Nexperia"
			(at 280.67 151.765 0)
			(effects
				(font
					(size 1.27 1.27)
					(thickness 0.15)
				)
				(justify left bottom)
				(hide yes)
			)
		)
		(property "Author" "Antmicro"
			(at 280.67 154.305 0)
			(effects
				(font
					(size 1.27 1.27)
					(thickness 0.15)
				)
				(justify left bottom)
				(hide yes)
			)
		)
		(property "License" "Apache-2.0"
			(at 280.67 156.845 0)
			(effects
				(font
					(size 1.27 1.27)
					(thickness 0.15)
				)
				(justify left bottom)
				(hide yes)
			)
		)
		(pin "1"
		)
		(pin "10"
		)
		(pin "2"
		)
		(pin "3"
		)
		(pin "4"
		)
		(pin "5"
		)
		(pin "6"
		)
		(pin "7"
		)
		(pin "8"
		)
		(pin "9"
		)
		(instances
			(project "gmsl-serializer"
				(path ""
					(reference "D1")
					(unit 1)
				)
			)
		)
	)
	(symbol
		(lib_id "antmicroResistors0402:R_100R_0402")
		(at 185.42 181.61 0)
		(unit 1)
		(exclude_from_sim no)
		(in_bom yes)
		(on_board yes)
		(dnp no)
		(property "Reference" "R25"
			(at 185.42 180.34 0)
			(effects
				(font
					(size 1.27 1.27)
					(thickness 0.15)
				)
				(justify right)
			)
		)
		(property "Value" "R_100R_0402"
			(at 205.74 194.31 0)
			(effects
				(font
					(size 1.27 1.27)
					(thickness 0.15)
				)
				(justify left bottom)
				(hide yes)
			)
		)
		(property "Footprint" "antmicro-footprints:R_0402_1005Metric"
			(at 205.74 196.85 0)
			(effects
				(font
					(size 1.27 1.27)
					(thickness 0.15)
				)
				(justify left bottom)
				(hide yes)
			)
		)
		(property "Datasheet" "https://www.bourns.com/docs/product-datasheets/cr.pdf"
			(at 205.74 199.39 0)
			(effects
				(font
					(size 1.27 1.27)
					(thickness 0.15)
				)
				(justify left bottom)
				(hide yes)
			)
		)
		(property "Description" ""
			(at 185.42 181.61 0)
			(effects
				(font
					(size 1.27 1.27)
				)
				(hide yes)
			)
		)
		(property "MPN" "CR0402-FX-1000GLF"
			(at 205.74 201.93 0)
			(effects
				(font
					(size 1.27 1.27)
					(thickness 0.15)
				)
				(justify left bottom)
				(hide yes)
			)
		)
		(property "Manufacturer" "Bourns"
			(at 205.74 204.47 0)
			(effects
				(font
					(size 1.27 1.27)
					(thickness 0.15)
				)
				(justify left bottom)
				(hide yes)
			)
		)
		(property "License" "Apache-2.0"
			(at 205.74 207.01 0)
			(effects
				(font
					(size 1.27 1.27)
					(thickness 0.15)
				)
				(justify left bottom)
				(hide yes)
			)
		)
		(property "Author" "Antmicro"
			(at 205.74 209.55 0)
			(effects
				(font
					(size 1.27 1.27)
					(thickness 0.15)
				)
				(justify left bottom)
				(hide yes)
			)
		)
		(property "Val" "100R"
			(at 193.04 180.34 0)
			(effects
				(font
					(size 1.27 1.27)
					(thickness 0.15)
				)
			)
		)
		(property "Tolerance" "1%"
			(at 205.74 191.77 0)
			(effects
				(font
					(size 1.27 1.27)
				)
				(justify left bottom)
				(hide yes)
			)
		)
		(pin "1"
		)
		(pin "2"
		)
		(instances
			(project "gmsl-serializer"
				(path ""
					(reference "R25")
					(unit 1)
				)
			)
		)
	)
	(symbol
		(lib_id "antmicroResistors0402:R_100R_0402")
		(at 185.42 173.99 0)
		(unit 1)
		(exclude_from_sim no)
		(in_bom yes)
		(on_board yes)
		(dnp no)
		(property "Reference" "R3"
			(at 185.42 172.72 0)
			(effects
				(font
					(size 1.27 1.27)
					(thickness 0.15)
				)
				(justify right)
			)
		)
		(property "Value" "R_100R_0402"
			(at 205.74 186.69 0)
			(effects
				(font
					(size 1.27 1.27)
					(thickness 0.15)
				)
				(justify left bottom)
				(hide yes)
			)
		)
		(property "Footprint" "antmicro-footprints:R_0402_1005Metric"
			(at 205.74 189.23 0)
			(effects
				(font
					(size 1.27 1.27)
					(thickness 0.15)
				)
				(justify left bottom)
				(hide yes)
			)
		)
		(property "Datasheet" "https://www.bourns.com/docs/product-datasheets/cr.pdf"
			(at 205.74 191.77 0)
			(effects
				(font
					(size 1.27 1.27)
					(thickness 0.15)
				)
				(justify left bottom)
				(hide yes)
			)
		)
		(property "Description" ""
			(at 185.42 173.99 0)
			(effects
				(font
					(size 1.27 1.27)
				)
				(hide yes)
			)
		)
		(property "MPN" "CR0402-FX-1000GLF"
			(at 205.74 194.31 0)
			(effects
				(font
					(size 1.27 1.27)
					(thickness 0.15)
				)
				(justify left bottom)
				(hide yes)
			)
		)
		(property "Manufacturer" "Bourns"
			(at 205.74 196.85 0)
			(effects
				(font
					(size 1.27 1.27)
					(thickness 0.15)
				)
				(justify left bottom)
				(hide yes)
			)
		)
		(property "License" "Apache-2.0"
			(at 205.74 199.39 0)
			(effects
				(font
					(size 1.27 1.27)
					(thickness 0.15)
				)
				(justify left bottom)
				(hide yes)
			)
		)
		(property "Author" "Antmicro"
			(at 205.74 201.93 0)
			(effects
				(font
					(size 1.27 1.27)
					(thickness 0.15)
				)
				(justify left bottom)
				(hide yes)
			)
		)
		(property "Val" "100R"
			(at 193.04 172.72 0)
			(effects
				(font
					(size 1.27 1.27)
					(thickness 0.15)
				)
			)
		)
		(property "Tolerance" "1%"
			(at 205.74 184.15 0)
			(effects
				(font
					(size 1.27 1.27)
				)
				(justify left bottom)
				(hide yes)
			)
		)
		(pin "1"
		)
		(pin "2"
		)
		(instances
			(project "gmsl-serializer"
				(path ""
					(reference "R3")
					(unit 1)
				)
			)
		)
	)
	(symbol
		(lib_id "antmicropower:+3V3")
		(at 173.99 193.04 0)
		(unit 1)
		(exclude_from_sim no)
		(in_bom yes)
		(on_board yes)
		(dnp no)
		(fields_autoplaced yes)
		(property "Reference" "#PWR01"
			(at 189.23 195.58 0)
			(effects
				(font
					(size 1.27 1.27)
					(thickness 0.15)
				)
				(justify left bottom)
				(hide yes)
			)
		)
		(property "Value" "+3V3"
			(at 173.99 187.96 0)
			(effects
				(font
					(size 1.27 1.27)
					(thickness 0.15)
				)
			)
		)
		(property "Footprint" ""
			(at 189.23 200.66 0)
			(effects
				(font
					(size 1.27 1.27)
					(thickness 0.15)
				)
				(justify left bottom)
				(hide yes)
			)
		)
		(property "Datasheet" ""
			(at 189.23 203.2 0)
			(effects
				(font
					(size 1.27 1.27)
					(thickness 0.15)
				)
				(justify left bottom)
				(hide yes)
			)
		)
		(property "Description" ""
			(at 173.99 193.04 0)
			(effects
				(font
					(size 1.27 1.27)
				)
				(hide yes)
			)
		)
		(property "Author" "Antmicro"
			(at 189.23 200.66 0)
			(effects
				(font
					(size 1.27 1.27)
					(thickness 0.15)
				)
				(justify left bottom)
				(hide yes)
			)
		)
		(property "License" "Apache-2.0"
			(at 189.23 203.2 0)
			(effects
				(font
					(size 1.27 1.27)
					(thickness 0.15)
				)
				(justify left bottom)
				(hide yes)
			)
		)
		(pin "1"
		)
		(instances
			(project "gmsl-serializer"
				(path ""
					(reference "#PWR01")
					(unit 1)
				)
			)
		)
	)
	(symbol
		(lib_id "antmicroFCCConnectors:Conn_FFC_WE_68715014022")
		(at 161.29 77.47 0)
		(mirror y)
		(unit 1)
		(exclude_from_sim no)
		(in_bom yes)
		(on_board yes)
		(dnp no)
		(fields_autoplaced yes)
		(property "Reference" "J1"
			(at 155.575 71.12 0)
			(effects
				(font
					(size 1.27 1.27)
					(thickness 0.15)
				)
			)
		)
		(property "Value" "Conn_FFC_WE_68715014022"
			(at 155.575 73.66 0)
			(effects
				(font
					(size 1.27 1.27)
					(thickness 0.15)
				)
				(hide yes)
			)
		)
		(property "Footprint" "antmicro-footprints:Conn_FFC_WE_68715014x22"
			(at 142.24 87.63 0)
			(effects
				(font
					(size 1.27 1.27)
					(thickness 0.15)
				)
				(justify left bottom)
				(hide yes)
			)
		)
		(property "Datasheet" "https://www.we-online.com/components/products/datasheet/68715014022.pdf"
			(at 142.24 90.17 0)
			(effects
				(font
					(size 1.27 1.27)
					(thickness 0.15)
				)
				(justify left bottom)
				(hide yes)
			)
		)
		(property "Description" ""
			(at 161.29 77.47 0)
			(effects
				(font
					(size 1.27 1.27)
				)
				(hide yes)
			)
		)
		(property "MPN" "68715014022"
			(at 155.575 73.66 0)
			(effects
				(font
					(size 1.27 1.27)
					(thickness 0.15)
				)
			)
		)
		(property "Manufacturer" "Würth Elektronik"
			(at 142.24 95.25 0)
			(effects
				(font
					(size 1.27 1.27)
					(thickness 0.15)
				)
				(justify left bottom)
				(hide yes)
			)
		)
		(property "Author" "Antmicro"
			(at 142.24 97.79 0)
			(effects
				(font
					(size 1.27 1.27)
					(thickness 0.15)
				)
				(justify left bottom)
				(hide yes)
			)
		)
		(property "License" "Apache-2.0"
			(at 142.24 100.33 0)
			(effects
				(font
					(size 1.27 1.27)
					(thickness 0.15)
				)
				(justify left bottom)
				(hide yes)
			)
		)
		(pin "1"
		)
		(pin "10"
		)
		(pin "11"
		)
		(pin "12"
		)
		(pin "13"
		)
		(pin "14"
		)
		(pin "15"
		)
		(pin "16"
		)
		(pin "17"
		)
		(pin "18"
		)
		(pin "19"
		)
		(pin "2"
		)
		(pin "20"
		)
		(pin "21"
		)
		(pin "22"
		)
		(pin "23"
		)
		(pin "24"
		)
		(pin "25"
		)
		(pin "26"
		)
		(pin "27"
		)
		(pin "28"
		)
		(pin "29"
		)
		(pin "3"
		)
		(pin "30"
		)
		(pin "31"
		)
		(pin "32"
		)
		(pin "33"
		)
		(pin "34"
		)
		(pin "35"
		)
		(pin "36"
		)
		(pin "37"
		)
		(pin "38"
		)
		(pin "39"
		)
		(pin "4"
		)
		(pin "40"
		)
		(pin "41"
		)
		(pin "42"
		)
		(pin "43"
		)
		(pin "44"
		)
		(pin "45"
		)
		(pin "46"
		)
		(pin "47"
		)
		(pin "48"
		)
		(pin "49"
		)
		(pin "5"
		)
		(pin "50"
		)
		(pin "6"
		)
		(pin "7"
		)
		(pin "8"
		)
		(pin "9"
		)
		(pin "MP1"
		)
		(pin "MP2"
		)
		(instances
			(project "gmsl-serializer"
				(path ""
					(reference "J1")
					(unit 1)
				)
			)
		)
	)
	(symbol
		(lib_id "antmicroTVSDiodes:PESD4USB5U-TTS")
		(at 266.7 187.96 0)
		(unit 1)
		(exclude_from_sim no)
		(in_bom yes)
		(on_board yes)
		(dnp no)
		(property "Reference" "D4"
			(at 269.24 185.42 0)
			(effects
				(font
					(size 1.27 1.27)
					(thickness 0.15)
				)
				(justify left)
			)
		)
		(property "Value" "PESD4USB5U-TTS"
			(at 280.67 186.055 0)
			(effects
				(font
					(size 1.27 1.27)
					(thickness 0.15)
				)
				(justify left bottom)
				(hide yes)
			)
		)
		(property "Footprint" "antmicro-footprints:DFN-10_2.5x1mm"
			(at 280.67 188.595 0)
			(effects
				(font
					(size 1.27 1.27)
					(thickness 0.15)
				)
				(justify left bottom)
				(hide yes)
			)
		)
		(property "Datasheet" "https://assets.nexperia.com/documents/data-sheet/PESD4USB5U-TTS.pdf"
			(at 280.67 191.135 0)
			(effects
				(font
					(size 1.27 1.27)
					(thickness 0.15)
				)
				(justify left bottom)
				(hide yes)
			)
		)
		(property "Description" ""
			(at 266.7 187.96 0)
			(effects
				(font
					(size 1.27 1.27)
				)
				(hide yes)
			)
		)
		(property "MPN" "PESD4USB5U-TTS"
			(at 269.24 200.66 0)
			(effects
				(font
					(size 1.27 1.27)
					(thickness 0.15)
				)
				(justify left)
			)
		)
		(property "Manufacturer" "Nexperia"
			(at 280.67 196.215 0)
			(effects
				(font
					(size 1.27 1.27)
					(thickness 0.15)
				)
				(justify left bottom)
				(hide yes)
			)
		)
		(property "Author" "Antmicro"
			(at 280.67 198.755 0)
			(effects
				(font
					(size 1.27 1.27)
					(thickness 0.15)
				)
				(justify left bottom)
				(hide yes)
			)
		)
		(property "License" "Apache-2.0"
			(at 280.67 201.295 0)
			(effects
				(font
					(size 1.27 1.27)
					(thickness 0.15)
				)
				(justify left bottom)
				(hide yes)
			)
		)
		(pin "1"
		)
		(pin "10"
		)
		(pin "2"
		)
		(pin "3"
		)
		(pin "4"
		)
		(pin "5"
		)
		(pin "6"
		)
		(pin "7"
		)
		(pin "8"
		)
		(pin "9"
		)
		(instances
			(project "gmsl-serializer"
				(path ""
					(reference "D4")
					(unit 1)
				)
			)
		)
	)
	(symbol
		(lib_id "antmicroResistors0402:R_4k7_0402")
		(at 214.63 171.45 90)
		(unit 1)
		(exclude_from_sim no)
		(in_bom yes)
		(on_board yes)
		(dnp no)
		(property "Reference" "R6"
			(at 217.17 167.6399 90)
			(effects
				(font
					(size 1.27 1.27)
					(thickness 0.15)
				)
				(justify right)
			)
		)
		(property "Value" "R_4k7_0402"
			(at 227.33 151.13 0)
			(effects
				(font
					(size 1.27 1.27)
					(thickness 0.15)
				)
				(justify left bottom)
				(hide yes)
			)
		)
		(property "Footprint" "antmicro-footprints:R_0402_1005Metric"
			(at 229.87 151.13 0)
			(effects
				(font
					(size 1.27 1.27)
					(thickness 0.15)
				)
				(justify left bottom)
				(hide yes)
			)
		)
		(property "Datasheet" "https://www.bourns.com/docs/product-datasheets/cr.pdf"
			(at 232.41 151.13 0)
			(effects
				(font
					(size 1.27 1.27)
					(thickness 0.15)
				)
				(justify left bottom)
				(hide yes)
			)
		)
		(property "Description" ""
			(at 214.63 171.45 0)
			(effects
				(font
					(size 1.27 1.27)
				)
				(hide yes)
			)
		)
		(property "MPN" "CR0402-FX-4701GLF"
			(at 234.95 151.13 0)
			(effects
				(font
					(size 1.27 1.27)
					(thickness 0.15)
				)
				(justify left bottom)
				(hide yes)
			)
		)
		(property "Manufacturer" "Bourns"
			(at 237.49 151.13 0)
			(effects
				(font
					(size 1.27 1.27)
					(thickness 0.15)
				)
				(justify left bottom)
				(hide yes)
			)
		)
		(property "License" "Apache-2.0"
			(at 240.03 151.13 0)
			(effects
				(font
					(size 1.27 1.27)
					(thickness 0.15)
				)
				(justify left bottom)
				(hide yes)
			)
		)
		(property "Author" "Antmicro"
			(at 242.57 151.13 0)
			(effects
				(font
					(size 1.27 1.27)
					(thickness 0.15)
				)
				(justify left bottom)
				(hide yes)
			)
		)
		(property "Val" "4k7"
			(at 217.17 170.1799 90)
			(effects
				(font
					(size 1.27 1.27)
					(thickness 0.15)
				)
				(justify right)
			)
		)
		(property "Tolerance" "1%"
			(at 224.79 151.13 0)
			(effects
				(font
					(size 1.27 1.27)
				)
				(justify left bottom)
				(hide yes)
			)
		)
		(pin "1"
		)
		(pin "2"
		)
		(instances
			(project "gmsl-serializer"
				(path ""
					(reference "R6")
					(unit 1)
				)
			)
		)
	)
	(symbol
		(lib_id "antmicroResistors0402:R_10k_0402")
		(at 175.26 161.29 0)
		(unit 1)
		(exclude_from_sim no)
		(in_bom yes)
		(on_board yes)
		(dnp no)
		(property "Reference" "R1"
			(at 173.99 160.02 0)
			(effects
				(font
					(size 1.27 1.27)
					(thickness 0.15)
				)
			)
		)
		(property "Value" "R_10k_0402"
			(at 195.58 173.99 0)
			(effects
				(font
					(size 1.27 1.27)
					(thickness 0.15)
				)
				(justify left bottom)
				(hide yes)
			)
		)
		(property "Footprint" "antmicro-footprints:R_0402_1005Metric"
			(at 195.58 176.53 0)
			(effects
				(font
					(size 1.27 1.27)
					(thickness 0.15)
				)
				(justify left bottom)
				(hide yes)
			)
		)
		(property "Datasheet" "https://www.bourns.com/docs/product-datasheets/cr.pdf"
			(at 195.58 179.07 0)
			(effects
				(font
					(size 1.27 1.27)
					(thickness 0.15)
				)
				(justify left bottom)
				(hide yes)
			)
		)
		(property "Description" ""
			(at 175.26 161.29 0)
			(effects
				(font
					(size 1.27 1.27)
				)
				(hide yes)
			)
		)
		(property "MPN" "CR0402-FX-1002GLF"
			(at 195.58 181.61 0)
			(effects
				(font
					(size 1.27 1.27)
					(thickness 0.15)
				)
				(justify left bottom)
				(hide yes)
			)
		)
		(property "Manufacturer" "Bourns"
			(at 195.58 184.15 0)
			(effects
				(font
					(size 1.27 1.27)
					(thickness 0.15)
				)
				(justify left bottom)
				(hide yes)
			)
		)
		(property "License" "Apache-2.0"
			(at 195.58 186.69 0)
			(effects
				(font
					(size 1.27 1.27)
					(thickness 0.15)
				)
				(justify left bottom)
				(hide yes)
			)
		)
		(property "Author" "Antmicro"
			(at 195.58 189.23 0)
			(effects
				(font
					(size 1.27 1.27)
					(thickness 0.15)
				)
				(justify left bottom)
				(hide yes)
			)
		)
		(property "Val" "10k"
			(at 181.61 160.02 0)
			(effects
				(font
					(size 1.27 1.27)
					(thickness 0.15)
				)
			)
		)
		(property "Tolerance" "1%"
			(at 195.58 171.45 0)
			(effects
				(font
					(size 1.27 1.27)
				)
				(justify left bottom)
				(hide yes)
			)
		)
		(pin "1"
		)
		(pin "2"
		)
		(instances
			(project "gmsl-serializer"
				(path ""
					(reference "R1")
					(unit 1)
				)
			)
		)
	)
	(symbol
		(lib_id "antmicropower:GND")
		(at 265.43 176.53 0)
		(unit 1)
		(exclude_from_sim no)
		(in_bom yes)
		(on_board yes)
		(dnp no)
		(property "Reference" "#PWR0140"
			(at 274.32 179.07 0)
			(effects
				(font
					(size 1.27 1.27)
					(thickness 0.15)
				)
				(justify left bottom)
				(hide yes)
			)
		)
		(property "Value" "GND"
			(at 265.43 180.34 0)
			(effects
				(font
					(size 1.27 1.27)
					(thickness 0.15)
				)
			)
		)
		(property "Footprint" ""
			(at 274.32 184.15 0)
			(effects
				(font
					(size 1.27 1.27)
					(thickness 0.15)
				)
				(justify left bottom)
				(hide yes)
			)
		)
		(property "Datasheet" ""
			(at 274.32 189.23 0)
			(effects
				(font
					(size 1.27 1.27)
					(thickness 0.15)
				)
				(justify left bottom)
				(hide yes)
			)
		)
		(property "Description" ""
			(at 265.43 176.53 0)
			(effects
				(font
					(size 1.27 1.27)
				)
				(hide yes)
			)
		)
		(property "Author" "Antmicro"
			(at 274.32 184.15 0)
			(effects
				(font
					(size 1.27 1.27)
					(thickness 0.15)
				)
				(justify left bottom)
				(hide yes)
			)
		)
		(property "License" "Apache-2.0"
			(at 274.32 186.69 0)
			(effects
				(font
					(size 1.27 1.27)
					(thickness 0.15)
				)
				(justify left bottom)
				(hide yes)
			)
		)
		(pin "1"
		)
		(instances
			(project "gmsl-serializer"
				(path ""
					(reference "#PWR0140")
					(unit 1)
				)
			)
		)
	)
	(symbol
		(lib_id "antmicroResistors0402:R_100R_0402")
		(at 185.42 179.07 0)
		(unit 1)
		(exclude_from_sim no)
		(in_bom yes)
		(on_board yes)
		(dnp no)
		(property "Reference" "R24"
			(at 185.42 177.8 0)
			(effects
				(font
					(size 1.27 1.27)
					(thickness 0.15)
				)
				(justify right)
			)
		)
		(property "Value" "R_100R_0402"
			(at 205.74 191.77 0)
			(effects
				(font
					(size 1.27 1.27)
					(thickness 0.15)
				)
				(justify left bottom)
				(hide yes)
			)
		)
		(property "Footprint" "antmicro-footprints:R_0402_1005Metric"
			(at 205.74 194.31 0)
			(effects
				(font
					(size 1.27 1.27)
					(thickness 0.15)
				)
				(justify left bottom)
				(hide yes)
			)
		)
		(property "Datasheet" "https://www.bourns.com/docs/product-datasheets/cr.pdf"
			(at 205.74 196.85 0)
			(effects
				(font
					(size 1.27 1.27)
					(thickness 0.15)
				)
				(justify left bottom)
				(hide yes)
			)
		)
		(property "Description" ""
			(at 185.42 179.07 0)
			(effects
				(font
					(size 1.27 1.27)
				)
				(hide yes)
			)
		)
		(property "MPN" "CR0402-FX-1000GLF"
			(at 205.74 199.39 0)
			(effects
				(font
					(size 1.27 1.27)
					(thickness 0.15)
				)
				(justify left bottom)
				(hide yes)
			)
		)
		(property "Manufacturer" "Bourns"
			(at 205.74 201.93 0)
			(effects
				(font
					(size 1.27 1.27)
					(thickness 0.15)
				)
				(justify left bottom)
				(hide yes)
			)
		)
		(property "License" "Apache-2.0"
			(at 205.74 204.47 0)
			(effects
				(font
					(size 1.27 1.27)
					(thickness 0.15)
				)
				(justify left bottom)
				(hide yes)
			)
		)
		(property "Author" "Antmicro"
			(at 205.74 207.01 0)
			(effects
				(font
					(size 1.27 1.27)
					(thickness 0.15)
				)
				(justify left bottom)
				(hide yes)
			)
		)
		(property "Val" "100R"
			(at 193.04 177.8 0)
			(effects
				(font
					(size 1.27 1.27)
					(thickness 0.15)
				)
			)
		)
		(property "Tolerance" "1%"
			(at 205.74 189.23 0)
			(effects
				(font
					(size 1.27 1.27)
				)
				(justify left bottom)
				(hide yes)
			)
		)
		(pin "1"
		)
		(pin "2"
		)
		(instances
			(project "gmsl-serializer"
				(path ""
					(reference "R24")
					(unit 1)
				)
			)
		)
	)
	(symbol
		(lib_id "antmicroResistors0402:R_100R_0402")
		(at 185.42 176.53 0)
		(unit 1)
		(exclude_from_sim no)
		(in_bom yes)
		(on_board yes)
		(dnp no)
		(property "Reference" "R4"
			(at 185.42 175.26 0)
			(effects
				(font
					(size 1.27 1.27)
					(thickness 0.15)
				)
				(justify right)
			)
		)
		(property "Value" "R_100R_0402"
			(at 205.74 189.23 0)
			(effects
				(font
					(size 1.27 1.27)
					(thickness 0.15)
				)
				(justify left bottom)
				(hide yes)
			)
		)
		(property "Footprint" "antmicro-footprints:R_0402_1005Metric"
			(at 205.74 191.77 0)
			(effects
				(font
					(size 1.27 1.27)
					(thickness 0.15)
				)
				(justify left bottom)
				(hide yes)
			)
		)
		(property "Datasheet" "https://www.bourns.com/docs/product-datasheets/cr.pdf"
			(at 205.74 194.31 0)
			(effects
				(font
					(size 1.27 1.27)
					(thickness 0.15)
				)
				(justify left bottom)
				(hide yes)
			)
		)
		(property "Description" ""
			(at 185.42 176.53 0)
			(effects
				(font
					(size 1.27 1.27)
				)
				(hide yes)
			)
		)
		(property "MPN" "CR0402-FX-1000GLF"
			(at 205.74 196.85 0)
			(effects
				(font
					(size 1.27 1.27)
					(thickness 0.15)
				)
				(justify left bottom)
				(hide yes)
			)
		)
		(property "Manufacturer" "Bourns"
			(at 205.74 199.39 0)
			(effects
				(font
					(size 1.27 1.27)
					(thickness 0.15)
				)
				(justify left bottom)
				(hide yes)
			)
		)
		(property "License" "Apache-2.0"
			(at 205.74 201.93 0)
			(effects
				(font
					(size 1.27 1.27)
					(thickness 0.15)
				)
				(justify left bottom)
				(hide yes)
			)
		)
		(property "Author" "Antmicro"
			(at 205.74 204.47 0)
			(effects
				(font
					(size 1.27 1.27)
					(thickness 0.15)
				)
				(justify left bottom)
				(hide yes)
			)
		)
		(property "Val" "100R"
			(at 193.04 175.26 0)
			(effects
				(font
					(size 1.27 1.27)
					(thickness 0.15)
				)
			)
		)
		(property "Tolerance" "1%"
			(at 205.74 186.69 0)
			(effects
				(font
					(size 1.27 1.27)
				)
				(justify left bottom)
				(hide yes)
			)
		)
		(pin "1"
		)
		(pin "2"
		)
		(instances
			(project "gmsl-serializer"
				(path ""
					(reference "R4")
					(unit 1)
				)
			)
		)
	)
	(symbol
		(lib_id "antmicropower:GND")
		(at 265.43 154.94 0)
		(unit 1)
		(exclude_from_sim no)
		(in_bom yes)
		(on_board yes)
		(dnp no)
		(property "Reference" "#PWR0104"
			(at 274.32 157.48 0)
			(effects
				(font
					(size 1.27 1.27)
					(thickness 0.15)
				)
				(justify left bottom)
				(hide yes)
			)
		)
		(property "Value" "GND"
			(at 265.43 158.75 0)
			(effects
				(font
					(size 1.27 1.27)
					(thickness 0.15)
				)
			)
		)
		(property "Footprint" ""
			(at 274.32 162.56 0)
			(effects
				(font
					(size 1.27 1.27)
					(thickness 0.15)
				)
				(justify left bottom)
				(hide yes)
			)
		)
		(property "Datasheet" ""
			(at 274.32 167.64 0)
			(effects
				(font
					(size 1.27 1.27)
					(thickness 0.15)
				)
				(justify left bottom)
				(hide yes)
			)
		)
		(property "Description" ""
			(at 265.43 154.94 0)
			(effects
				(font
					(size 1.27 1.27)
				)
				(hide yes)
			)
		)
		(property "Author" "Antmicro"
			(at 274.32 162.56 0)
			(effects
				(font
					(size 1.27 1.27)
					(thickness 0.15)
				)
				(justify left bottom)
				(hide yes)
			)
		)
		(property "License" "Apache-2.0"
			(at 274.32 165.1 0)
			(effects
				(font
					(size 1.27 1.27)
					(thickness 0.15)
				)
				(justify left bottom)
				(hide yes)
			)
		)
		(pin "1"
		)
		(instances
			(project "gmsl-serializer"
				(path ""
					(reference "#PWR0104")
					(unit 1)
				)
			)
		)
	)
)
